(kicad_pcb
	(version 20260206)
	(generator "pcbnew")
	(generator_version "10.0")
	(general
		(thickness 1.6)
		(legacy_teardrops no)
	)
	(paper "A4")
	(title_block
		(title "03242023_DA0F0TMBIJ0_F0T_Motherboard_J_brd_V01_OCP.brd")
		(comment 1 "Grand Teton / footprints 4404-4409 of 6105")
	)
	(layers
		(0 "F.Cu" signal "TOP")
		(4 "In1.Cu" signal "GND")
		(6 "In2.Cu" signal "IN1")
		(8 "In3.Cu" signal "GND1")
		(10 "In4.Cu" signal "IN2")
		(12 "In5.Cu" signal "GND2")
		(14 "In6.Cu" signal "IN3")
		(16 "In7.Cu" signal "GND3")
		(18 "In8.Cu" signal "VCC")
		(20 "In9.Cu" signal "VCC1")
		(22 "In10.Cu" signal "GND4")
		(24 "In11.Cu" signal "IN4")
		(26 "In12.Cu" signal "GND5")
		(28 "In13.Cu" signal "IN5")
		(30 "In14.Cu" signal "GND6")
		(32 "In15.Cu" signal "IN6")
		(34 "In16.Cu" signal "GND7")
		(2 "B.Cu" signal "BOTTOM")
		(9 "F.Adhes" user "F.Adhesive")
		(11 "B.Adhes" user "B.Adhesive")
		(13 "F.Paste" user "Package Geometry/Pastemask Top")
		(15 "B.Paste" user "Package Geometry/Pastemask Bottom")
		(5 "F.SilkS" user "Ref Des/Silkscreen Top")
		(7 "B.SilkS" user "Ref Des/Silkscreen Bottom")
		(1 "F.Mask" user "Board Geometry/Soldermask Top")
		(3 "B.Mask" user "Board Geometry/Soldermask Bottom")
		(17 "Dwgs.User" user "User.Drawings")
		(19 "Cmts.User" user "User.Comments")
		(21 "Eco1.User" user "User.Eco1")
		(23 "Eco2.User" user "User.Eco2")
		(25 "Edge.Cuts" user "Board Geometry/Outline")
		(27 "Margin" user)
		(31 "F.CrtYd" user "Package Geometry/Place Bound Top")
		(29 "B.CrtYd" user "Package Geometry/Place Bound Bottom")
		(35 "F.Fab" user "Ref Des/Assembly Top")
		(33 "B.Fab" user "Ref Des/Assembly Bottom")
	)
	(footprint ""
		(layer "B.Cu")
		(at 346.497148 -32.58439 180)
		(property "Reference" "R2342"
			(at 0 0 0)
			(layer "B.SilkS")
			(hide yes)
			(effects
				(font
					(size 1.27 1.27)
				)
				(justify mirror)
			)
		)
		(property "Value" ""
			(at 0 0 0)
			(layer "B.Fab")
			(effects
				(font
					(size 1.27 1.27)
				)
				(justify mirror)
			)
		)
		(duplicate_pad_numbers_are_jumpers no)
		(fp_line
			(start 0.7874 0.4064)
			(end 0.7874 -0.4064)
			(stroke
				(width 0.1524)
				(type default)
			)
			(layer "B.SilkS")
		)
		(fp_line
			(start 0.7874 -0.4064)
			(end -0.7874 -0.4064)
			(stroke
				(width 0.1524)
				(type default)
			)
			(layer "B.SilkS")
		)
		(fp_line
			(start -0.7874 0.4064)
			(end 0.7874 0.4064)
			(stroke
				(width 0.1524)
				(type default)
			)
			(layer "B.SilkS")
		)
		(fp_line
			(start -0.7874 -0.4064)
			(end -0.7874 0.4064)
			(stroke
				(width 0.1524)
				(type default)
			)
			(layer "B.SilkS")
		)
		(fp_line
			(start 0.67945 0.3048)
			(end 0.67945 -0.305054)
			(stroke
				(width 0.1)
				(type default)
			)
			(layer "B.Fab")
		)
		(fp_line
			(start 0.67945 -0.305054)
			(end 0.12065 -0.305054)
			(stroke
				(width 0.1)
				(type default)
			)
			(layer "B.Fab")
		)
		(fp_line
			(start 0.12065 0.3048)
			(end 0.67945 0.3048)
			(stroke
				(width 0.1)
				(type default)
			)
			(layer "B.Fab")
		)
		(fp_line
			(start 0.12065 0.2794)
			(end 0.12065 0.3048)
			(stroke
				(width 0.1)
				(type default)
			)
			(layer "B.Fab")
		)
		(fp_line
			(start 0.12065 -0.2794)
			(end -0.12065 -0.2794)
			(stroke
				(width 0.1)
				(type default)
			)
			(layer "B.Fab")
		)
		(fp_line
			(start 0.12065 -0.305054)
			(end 0.12065 -0.2794)
			(stroke
				(width 0.1)
				(type default)
			)
			(layer "B.Fab")
		)
		(fp_line
			(start -0.120396 0.3048)
			(end -0.120396 0.2794)
			(stroke
				(width 0.1)
				(type default)
			)
			(layer "B.Fab")
		)
		(fp_line
			(start -0.120396 0.2794)
			(end 0.12065 0.2794)
			(stroke
				(width 0.1)
				(type default)
			)
			(layer "B.Fab")
		)
		(fp_line
			(start -0.12065 -0.2794)
			(end -0.12065 -0.3048)
			(stroke
				(width 0.1)
				(type default)
			)
			(layer "B.Fab")
		)
		(fp_line
			(start -0.12065 -0.3048)
			(end -0.67945 -0.3048)
			(stroke
				(width 0.1)
				(type default)
			)
			(layer "B.Fab")
		)
		(fp_line
			(start -0.67945 0.3048)
			(end -0.120396 0.3048)
			(stroke
				(width 0.1)
				(type default)
			)
			(layer "B.Fab")
		)
		(fp_line
			(start -0.67945 -0.3048)
			(end -0.67945 0.3048)
			(stroke
				(width 0.1)
				(type default)
			)
			(layer "B.Fab")
		)
		(pad "1" smd circle
			(at 0.40005 0)
			(size 0 0)
			(layers "B.Cu" "B.Mask" "B.Paste")
			(net "P3V3_AUX")
		)
		(pad "2" smd circle
			(at -0.40005 0)
			(size 0 0)
			(layers "B.Cu" "B.Mask" "B.Paste")
			(net "FM_DEBUG_PORT_PRSNT_R_N")
		)
	)
	(footprint ""
		(layer "B.Cu")
		(at 327.060814 -28.84297 -90)
		(property "Reference" "R1461"
			(at 0 0 90)
			(layer "B.SilkS")
			(hide yes)
			(effects
				(font
					(size 1.27 1.27)
				)
				(justify mirror)
			)
		)
		(property "Value" ""
			(at 0 0 90)
			(layer "B.Fab")
			(effects
				(font
					(size 1.27 1.27)
				)
				(justify mirror)
			)
		)
		(duplicate_pad_numbers_are_jumpers no)
		(fp_line
			(start -0.7874 0.4064)
			(end 0.7874 0.4064)
			(stroke
				(width 0.1524)
				(type default)
			)
			(layer "B.SilkS")
		)
		(fp_line
			(start 0.7874 0.4064)
			(end 0.7874 -0.4064)
			(stroke
				(width 0.1524)
				(type default)
			)
			(layer "B.SilkS")
		)
		(fp_line
			(start -0.7874 -0.4064)
			(end -0.7874 0.4064)
			(stroke
				(width 0.1524)
				(type default)
			)
			(layer "B.SilkS")
		)
		(fp_line
			(start 0.7874 -0.4064)
			(end -0.7874 -0.4064)
			(stroke
				(width 0.1524)
				(type default)
			)
			(layer "B.SilkS")
		)
		(fp_line
			(start -0.67945 0.3048)
			(end -0.120396 0.3048)
			(stroke
				(width 0.1)
				(type default)
			)
			(layer "B.Fab")
		)
		(fp_line
			(start -0.120396 0.3048)
			(end -0.120396 0.2794)
			(stroke
				(width 0.1)
				(type default)
			)
			(layer "B.Fab")
		)
		(fp_line
			(start 0.12065 0.3048)
			(end 0.67945 0.3048)
			(stroke
				(width 0.1)
				(type default)
			)
			(layer "B.Fab")
		)
		(fp_line
			(start 0.67945 0.3048)
			(end 0.67945 -0.305054)
			(stroke
				(width 0.1)
				(type default)
			)
			(layer "B.Fab")
		)
		(fp_line
			(start -0.120396 0.2794)
			(end 0.12065 0.2794)
			(stroke
				(width 0.1)
				(type default)
			)
			(layer "B.Fab")
		)
		(fp_line
			(start 0.12065 0.2794)
			(end 0.12065 0.3048)
			(stroke
				(width 0.1)
				(type default)
			)
			(layer "B.Fab")
		)
		(fp_line
			(start -0.12065 -0.2794)
			(end -0.12065 -0.3048)
			(stroke
				(width 0.1)
				(type default)
			)
			(layer "B.Fab")
		)
		(fp_line
			(start 0.12065 -0.2794)
			(end -0.12065 -0.2794)
			(stroke
				(width 0.1)
				(type default)
			)
			(layer "B.Fab")
		)
		(fp_line
			(start -0.67945 -0.3048)
			(end -0.67945 0.3048)
			(stroke
				(width 0.1)
				(type default)
			)
			(layer "B.Fab")
		)
		(fp_line
			(start -0.12065 -0.3048)
			(end -0.67945 -0.3048)
			(stroke
				(width 0.1)
				(type default)
			)
			(layer "B.Fab")
		)
		(fp_line
			(start 0.12065 -0.305054)
			(end 0.12065 -0.2794)
			(stroke
				(width 0.1)
				(type default)
			)
			(layer "B.Fab")
		)
		(fp_line
			(start 0.67945 -0.305054)
			(end 0.12065 -0.305054)
			(stroke
				(width 0.1)
				(type default)
			)
			(layer "B.Fab")
		)
		(pad "1" smd circle
			(at 0.40005 0 90)
			(size 0 0)
			(layers "B.Cu" "B.Mask" "B.Paste")
			(net "FM_EUP_LOT6_N")
		)
		(pad "2" smd circle
			(at -0.40005 0 90)
			(size 0 0)
			(layers "B.Cu" "B.Mask" "B.Paste")
			(net "FM_SUSACK_N")
		)
	)
	(footprint ""
		(layer "B.Cu")
		(at 337.166712 -31.693358 90)
		(property "Reference" "R917"
			(at 0 0 90)
			(layer "B.SilkS")
			(hide yes)
			(effects
				(font
					(size 1.27 1.27)
				)
				(justify mirror)
			)
		)
		(property "Value" ""
			(at 0 0 90)
			(layer "B.Fab")
			(effects
				(font
					(size 1.27 1.27)
				)
				(justify mirror)
			)
		)
		(duplicate_pad_numbers_are_jumpers no)
		(fp_line
			(start 0.7874 -0.4064)
			(end -0.7874 -0.4064)
			(stroke
				(width 0.1524)
				(type default)
			)
			(layer "B.SilkS")
		)
		(fp_line
			(start -0.7874 -0.4064)
			(end -0.7874 0.4064)
			(stroke
				(width 0.1524)
				(type default)
			)
			(layer "B.SilkS")
		)
		(fp_line
			(start 0.7874 0.4064)
			(end 0.7874 -0.4064)
			(stroke
				(width 0.1524)
				(type default)
			)
			(layer "B.SilkS")
		)
		(fp_line
			(start -0.7874 0.4064)
			(end 0.7874 0.4064)
			(stroke
				(width 0.1524)
				(type default)
			)
			(layer "B.SilkS")
		)
		(fp_line
			(start 0.67945 -0.305054)
			(end 0.12065 -0.305054)
			(stroke
				(width 0.1)
				(type default)
			)
			(layer "B.Fab")
		)
		(fp_line
			(start 0.12065 -0.305054)
			(end 0.12065 -0.2794)
			(stroke
				(width 0.1)
				(type default)
			)
			(layer "B.Fab")
		)
		(fp_line
			(start -0.12065 -0.3048)
			(end -0.67945 -0.3048)
			(stroke
				(width 0.1)
				(type default)
			)
			(layer "B.Fab")
		)
		(fp_line
			(start -0.67945 -0.3048)
			(end -0.67945 0.3048)
			(stroke
				(width 0.1)
				(type default)
			)
			(layer "B.Fab")
		)
		(fp_line
			(start 0.12065 -0.2794)
			(end -0.12065 -0.2794)
			(stroke
				(width 0.1)
				(type default)
			)
			(layer "B.Fab")
		)
		(fp_line
			(start -0.12065 -0.2794)
			(end -0.12065 -0.3048)
			(stroke
				(width 0.1)
				(type default)
			)
			(layer "B.Fab")
		)
		(fp_line
			(start 0.12065 0.2794)
			(end 0.12065 0.3048)
			(stroke
				(width 0.1)
				(type default)
			)
			(layer "B.Fab")
		)
		(fp_line
			(start -0.120396 0.2794)
			(end 0.12065 0.2794)
			(stroke
				(width 0.1)
				(type default)
			)
			(layer "B.Fab")
		)
		(fp_line
			(start 0.67945 0.3048)
			(end 0.67945 -0.305054)
			(stroke
				(width 0.1)
				(type default)
			)
			(layer "B.Fab")
		)
		(fp_line
			(start 0.12065 0.3048)
			(end 0.67945 0.3048)
			(stroke
				(width 0.1)
				(type default)
			)
			(layer "B.Fab")
		)
		(fp_line
			(start -0.120396 0.3048)
			(end -0.120396 0.2794)
			(stroke
				(width 0.1)
				(type default)
			)
			(layer "B.Fab")
		)
		(fp_line
			(start -0.67945 0.3048)
			(end -0.120396 0.3048)
			(stroke
				(width 0.1)
				(type default)
			)
			(layer "B.Fab")
		)
		(pad "1" smd circle
			(at 0.40005 0 270)
			(size 0 0)
			(layers "B.Cu" "B.Mask" "B.Paste")
			(net "SPI_PCH_IO3")
		)
		(pad "2" smd circle
			(at -0.40005 0 270)
			(size 0 0)
			(layers "B.Cu" "B.Mask" "B.Paste")
			(net "SPI_SYS_HOLD_IO3")
		)
	)
	(footprint ""
		(layer "B.Cu")
		(at 325.707502 -343.927938 -90)
		(property "Reference" "PR135"
			(at 0 0 90)
			(layer "B.SilkS")
			(hide yes)
			(effects
				(font
					(size 1.27 1.27)
				)
				(justify mirror)
			)
		)
		(property "Value" ""
			(at 0 0 90)
			(layer "B.Fab")
			(effects
				(font
					(size 1.27 1.27)
				)
				(justify mirror)
			)
		)
		(duplicate_pad_numbers_are_jumpers no)
		(fp_line
			(start -0.7874 0.4064)
			(end 0.7874 0.4064)
			(stroke
				(width 0.1524)
				(type default)
			)
			(layer "B.SilkS")
		)
		(fp_line
			(start 0.7874 0.4064)
			(end 0.7874 -0.4064)
			(stroke
				(width 0.1524)
				(type default)
			)
			(layer "B.SilkS")
		)
		(fp_line
			(start -0.7874 -0.4064)
			(end -0.7874 0.4064)
			(stroke
				(width 0.1524)
				(type default)
			)
			(layer "B.SilkS")
		)
		(fp_line
			(start 0.7874 -0.4064)
			(end -0.7874 -0.4064)
			(stroke
				(width 0.1524)
				(type default)
			)
			(layer "B.SilkS")
		)
		(fp_line
			(start -0.67945 0.3048)
			(end -0.120396 0.3048)
			(stroke
				(width 0.1)
				(type default)
			)
			(layer "B.Fab")
		)
		(fp_line
			(start -0.120396 0.3048)
			(end -0.120396 0.2794)
			(stroke
				(width 0.1)
				(type default)
			)
			(layer "B.Fab")
		)
		(fp_line
			(start 0.12065 0.3048)
			(end 0.67945 0.3048)
			(stroke
				(width 0.1)
				(type default)
			)
			(layer "B.Fab")
		)
		(fp_line
			(start 0.67945 0.3048)
			(end 0.67945 -0.305054)
			(stroke
				(width 0.1)
				(type default)
			)
			(layer "B.Fab")
		)
		(fp_line
			(start -0.120396 0.2794)
			(end 0.12065 0.2794)
			(stroke
				(width 0.1)
				(type default)
			)
			(layer "B.Fab")
		)
		(fp_line
			(start 0.12065 0.2794)
			(end 0.12065 0.3048)
			(stroke
				(width 0.1)
				(type default)
			)
			(layer "B.Fab")
		)
		(fp_line
			(start -0.12065 -0.2794)
			(end -0.12065 -0.3048)
			(stroke
				(width 0.1)
				(type default)
			)
			(layer "B.Fab")
		)
		(fp_line
			(start 0.12065 -0.2794)
			(end -0.12065 -0.2794)
			(stroke
				(width 0.1)
				(type default)
			)
			(layer "B.Fab")
		)
		(fp_line
			(start -0.67945 -0.3048)
			(end -0.67945 0.3048)
			(stroke
				(width 0.1)
				(type default)
			)
			(layer "B.Fab")
		)
		(fp_line
			(start -0.12065 -0.3048)
			(end -0.67945 -0.3048)
			(stroke
				(width 0.1)
				(type default)
			)
			(layer "B.Fab")
		)
		(fp_line
			(start 0.12065 -0.305054)
			(end 0.12065 -0.2794)
			(stroke
				(width 0.1)
				(type default)
			)
			(layer "B.Fab")
		)
		(fp_line
			(start 0.67945 -0.305054)
			(end 0.12065 -0.305054)
			(stroke
				(width 0.1)
				(type default)
			)
			(layer "B.Fab")
		)
		(pad "1" smd circle
			(at 0.40005 0 90)
			(size 0 0)
			(layers "B.Cu" "B.Mask" "B.Paste")
			(net "PVCCIN_CPU0_PVCC")
		)
		(pad "2" smd circle
			(at -0.40005 0 90)
			(size 0 0)
			(layers "B.Cu" "B.Mask" "B.Paste")
			(net "PVCCIN_CPU0_VDD7")
		)
	)
	(footprint ""
		(layer "B.Cu")
		(at 271.180814 -317.824358 180)
		(property "Reference" "R3879"
			(at 0 0 0)
			(layer "B.SilkS")
			(hide yes)
			(effects
				(font
					(size 1.27 1.27)
				)
				(justify mirror)
			)
		)
		(property "Value" ""
			(at 0 0 0)
			(layer "B.Fab")
			(effects
				(font
					(size 1.27 1.27)
				)
				(justify mirror)
			)
		)
		(duplicate_pad_numbers_are_jumpers no)
		(fp_line
			(start 0.7874 0.4064)
			(end 0.7874 -0.4064)
			(stroke
				(width 0.1524)
				(type default)
			)
			(layer "B.SilkS")
		)
		(fp_line
			(start 0.7874 -0.4064)
			(end -0.7874 -0.4064)
			(stroke
				(width 0.1524)
				(type default)
			)
			(layer "B.SilkS")
		)
		(fp_line
			(start -0.7874 0.4064)
			(end 0.7874 0.4064)
			(stroke
				(width 0.1524)
				(type default)
			)
			(layer "B.SilkS")
		)
		(fp_line
			(start -0.7874 -0.4064)
			(end -0.7874 0.4064)
			(stroke
				(width 0.1524)
				(type default)
			)
			(layer "B.SilkS")
		)
		(fp_line
			(start 0.67945 0.3048)
			(end 0.67945 -0.305054)
			(stroke
				(width 0.1)
				(type default)
			)
			(layer "B.Fab")
		)
		(fp_line
			(start 0.67945 -0.305054)
			(end 0.12065 -0.305054)
			(stroke
				(width 0.1)
				(type default)
			)
			(layer "B.Fab")
		)
		(fp_line
			(start 0.12065 0.3048)
			(end 0.67945 0.3048)
			(stroke
				(width 0.1)
				(type default)
			)
			(layer "B.Fab")
		)
		(fp_line
			(start 0.12065 0.2794)
			(end 0.12065 0.3048)
			(stroke
				(width 0.1)
				(type default)
			)
			(layer "B.Fab")
		)
		(fp_line
			(start 0.12065 -0.2794)
			(end -0.12065 -0.2794)
			(stroke
				(width 0.1)
				(type default)
			)
			(layer "B.Fab")
		)
		(fp_line
			(start 0.12065 -0.305054)
			(end 0.12065 -0.2794)
			(stroke
				(width 0.1)
				(type default)
			)
			(layer "B.Fab")
		)
		(fp_line
			(start -0.120396 0.3048)
			(end -0.120396 0.2794)
			(stroke
				(width 0.1)
				(type default)
			)
			(layer "B.Fab")
		)
		(fp_line
			(start -0.120396 0.2794)
			(end 0.12065 0.2794)
			(stroke
				(width 0.1)
				(type default)
			)
			(layer "B.Fab")
		)
		(fp_line
			(start -0.12065 -0.2794)
			(end -0.12065 -0.3048)
			(stroke
				(width 0.1)
				(type default)
			)
			(layer "B.Fab")
		)
		(fp_line
			(start -0.12065 -0.3048)
			(end -0.67945 -0.3048)
			(stroke
				(width 0.1)
				(type default)
			)
			(layer "B.Fab")
		)
		(fp_line
			(start -0.67945 0.3048)
			(end -0.120396 0.3048)
			(stroke
				(width 0.1)
				(type default)
			)
			(layer "B.Fab")
		)
		(fp_line
			(start -0.67945 -0.3048)
			(end -0.67945 0.3048)
			(stroke
				(width 0.1)
				(type default)
			)
			(layer "B.Fab")
		)
		(pad "1" smd circle
			(at 0.40005 0)
			(size 0 0)
			(layers "B.Cu" "B.Mask" "B.Paste")
			(net "I3C_SPD_DDRABCD_CPU0_LVC1_SCL_4")
		)
		(pad "2" smd circle
			(at -0.40005 0)
			(size 0 0)
			(layers "B.Cu" "B.Mask" "B.Paste")
			(net "I3C_SPD_DDRABCD_CPU0_LVC1_SCL")
		)
	)
	(footprint ""
		(layer "B.Cu")
		(at 100.306886 -357.53167)
		(property "Reference" "R2554"
			(at 0 0 0)
			(layer "B.SilkS")
			(hide yes)
			(effects
				(font
					(size 1.27 1.27)
				)
				(justify mirror)
			)
		)
		(property "Value" ""
			(at 0 0 0)
			(layer "B.Fab")
			(effects
				(font
					(size 1.27 1.27)
				)
				(justify mirror)
			)
		)
		(duplicate_pad_numbers_are_jumpers no)
		(fp_line
			(start -0.7874 -0.4064)
			(end -0.7874 0.4064)
			(stroke
				(width 0.1524)
				(type default)
			)
			(layer "B.SilkS")
		)
		(fp_line
			(start -0.7874 0.4064)
			(end 0.7874 0.4064)
			(stroke
				(width 0.1524)
				(type default)
			)
			(layer "B.SilkS")
		)
		(fp_line
			(start 0.7874 -0.4064)
			(end -0.7874 -0.4064)
			(stroke
				(width 0.1524)
				(type default)
			)
			(layer "B.SilkS")
		)
		(fp_line
			(start 0.7874 0.4064)
			(end 0.7874 -0.4064)
			(stroke
				(width 0.1524)
				(type default)
			)
			(layer "B.SilkS")
		)
		(fp_line
			(start -0.67945 -0.3048)
			(end -0.67945 0.3048)
			(stroke
				(width 0.1)
				(type default)
			)
			(layer "B.Fab")
		)
		(fp_line
			(start -0.67945 0.3048)
			(end -0.120396 0.3048)
			(stroke
				(width 0.1)
				(type default)
			)
			(layer "B.Fab")
		)
		(fp_line
			(start -0.12065 -0.3048)
			(end -0.67945 -0.3048)
			(stroke
				(width 0.1)
				(type default)
			)
			(layer "B.Fab")
		)
		(fp_line
			(start -0.12065 -0.2794)
			(end -0.12065 -0.3048)
			(stroke
				(width 0.1)
				(type default)
			)
			(layer "B.Fab")
		)
		(fp_line
			(start -0.120396 0.2794)
			(end 0.12065 0.2794)
			(stroke
				(width 0.1)
				(type default)
			)
			(layer "B.Fab")
		)
		(fp_line
			(start -0.120396 0.3048)
			(end -0.120396 0.2794)
			(stroke
				(width 0.1)
				(type default)
			)
			(layer "B.Fab")
		)
		(fp_line
			(start 0.12065 -0.305054)
			(end 0.12065 -0.2794)
			(stroke
				(width 0.1)
				(type default)
			)
			(layer "B.Fab")
		)
		(fp_line
			(start 0.12065 -0.2794)
			(end -0.12065 -0.2794)
			(stroke
				(width 0.1)
				(type default)
			)
			(layer "B.Fab")
		)
		(fp_line
			(start 0.12065 0.2794)
			(end 0.12065 0.3048)
			(stroke
				(width 0.1)
				(type default)
			)
			(layer "B.Fab")
		)
		(fp_line
			(start 0.12065 0.3048)
			(end 0.67945 0.3048)
			(stroke
				(width 0.1)
				(type default)
			)
			(layer "B.Fab")
		)
		(fp_line
			(start 0.67945 -0.305054)
			(end 0.12065 -0.305054)
			(stroke
				(width 0.1)
				(type default)
			)
			(layer "B.Fab")
		)
		(fp_line
			(start 0.67945 0.3048)
			(end 0.67945 -0.305054)
			(stroke
				(width 0.1)
				(type default)
			)
			(layer "B.Fab")
		)
		(pad "1" smd circle
			(at 0.40005 0 180)
			(size 0 0)
			(layers "B.Cu" "B.Mask" "B.Paste")
			(net "SVID_CLK0_CPU1_R")
		)
		(pad "2" smd circle
			(at -0.40005 0 180)
			(size 0 0)
			(layers "B.Cu" "B.Mask" "B.Paste")
			(net "PVNN_TERM_CPU1")
		)
	)
)
